FILE_TYPE = CONNECTIVITY;
{Allegro Design Entry HDL 16.6-p007 (v16-6-112F) 10/10/2012}
"PAGE_NUMBER" = 86;
0"NC";
1"M_L_DQ<63:0>";
2"M_L_CS_N<7:0>";
3"M_L_ECC<7:0>";
4"M_L_CKE<3:0>";
5"M_L_ODT<3:0>";
6"M_L_BA<1:0>";
7"M_L_MA<17:0>";
8"M_L_BG<1:0>";
9"M_L_CLK_DP<3:0>";
10"M_L_CLK_DN<3:0>";
11"M_L_DQS_DP<17:0>";
12"M_L_DQS_DN<17:0>";
13"GND\g";
14"GND\g";
15"GND\g";
16"P12V_NVDIMM_KLM\g";
17"GND\g";
18"PVPP_KLM\g";
19"PVDDQ_KLM\g";
20"PVTT_KLM\g";
21"PVPP_KLM\g";
22"M_L_DQS_DN<15>";
23"M_L_DQS_DP<14>";
24"M_L_DQS_DN<14>";
25"M_L_DQS_DP<13>";
26"M_L_DQS_DN<13>";
27"M_L_DQS_DP<12>";
28"M_L_DQS_DN<12>";
29"M_L_DQS_DN<11>";
30"M_L_DQS_DP<10>";
31"M_L_DQS_DN<4>";
32"M_L_DQS_DP<3>";
33"M_L_DQS_DN<3>";
34"M_L_DQS_DP<2>";
35"M_L_DQS_DN<2>";
36"M_L_DQS_DP<1>";
37"M_L_DQS_DN<1>";
38"M_L_DQ<62>";
39"M_L_DQ<61>";
40"M_L_DQ<54>";
41"M_L_DQS_DP<11>";
42"M_L_DQS_DP<9>";
43"M_L_DQS_DN<10>";
44"M_L_DQS_DN<9>";
45"M_L_DQS_DN<8>";
46"M_L_DQS_DN<7>";
47"M_L_DQS_DN<6>";
48"M_L_DQS_DN<5>";
49"M_L_DQS_DN<17>";
50"M_L_DQS_DN<16>";
51"M_L_DQS_DP<17>";
52"M_L_DQS_DP<16>";
53"M_L_DQS_DP<15>";
54"M_L_DQS_DP<8>";
55"M_L_DQS_DP<7>";
56"M_L_DQS_DP<6>";
57"M_L_DQS_DP<5>";
58"M_L_DQS_DN<0>";
59"M_L_DQS_DP<4>";
60"M_L_DQS_DP<0>";
61"M_L_DQ<58>";
62"M_L_DQ<57>";
63"M_L_DQ<55>";
64"M_L_DQ<56>";
65"M_L_DQ<59>";
66"M_L_DQ<60>";
67"M_L_DQ<63>";
68"M_L_MA<16>";
69"M_L_MA<15>";
70"M_L_MA<14>";
71"M_L_MA<11>";
72"M_L_MA<10>";
73"M_L_MA<9>";
74"M_L_MA<8>";
75"M_L_MA<17>";
76"M_L_MA<13>";
77"M_L_MA<12>";
78"M_L_DQ<47>";
79"M_L_DQ<48>";
80"M_L_DQ<49>";
81"M_L_DQ<50>";
82"M_L_DQ<51>";
83"M_L_DQ<52>";
84"M_L_DQ<53>";
85"M_L_DQ<44>";
86"M_L_DQ<45>";
87"M_L_DQ<46>";
88"M_L_DQ<38>";
89"M_L_DQ<36>";
90"M_L_DQ<35>";
91"M_L_DQ<33>";
92"M_L_DQ<34>";
93"M_L_DQ<37>";
94"M_L_DQ<39>";
95"M_L_DQ<40>";
96"M_L_DQ<41>";
97"M_L_DQ<42>";
98"M_L_DQ<43>";
99"M_L_DQ<26>";
100"M_L_DQ<27>";
101"M_L_DQ<23>";
102"M_L_DQ<24>";
103"M_L_DQ<25>";
104"M_L_DQ<30>";
105"M_L_DQ<31>";
106"M_L_DQ<32>";
107"M_L_DQ<28>";
108"M_L_DQ<29>";
109"M_L_DQ<17>";
110"M_L_DQ<15>";
111"M_L_DQ<13>";
112"M_L_DQ<14>";
113"M_L_DQ<16>";
114"M_L_DQ<18>";
115"M_L_DQ<19>";
116"M_L_DQ<20>";
117"M_L_DQ<21>";
118"M_L_DQ<22>";
119"M_L_CLK_DN<2>";
120"M_L_CLK_DN<3>";
121"M_L_CLK_DP<3>";
122"M_L_CLK_DP<2>";
123"M_L_BG<0>";
124"M_L_MA<2>";
125"M_L_BA<0>";
126"M_L_BG<1>";
127"M_L_MA<7>";
128"M_L_MA<6>";
129"M_L_MA<5>";
130"M_L_MA<4>";
131"M_L_MA<3>";
132"M_L_MA<1>";
133"M_L_MA<0>";
134"M_L_CS_N<7>";
135"M_L_BA<1>";
136"M_L_C<2>";
137"M_L_CS_N<4>";
138"M_L_CKE<2>";
139"M_L_ODT<3>";
140"M_L_ODT<2>";
141"M_L_ECC<7>";
142"M_L_CKE<3>";
143"M_L_ECC<0>";
144"M_L_ECC<1>";
145"M_L_ECC<2>";
146"M_L_ECC<3>";
147"M_L_ECC<4>";
148"M_L_ECC<5>";
149"M_L_ECC<6>";
150"M_L_CS_N<5>";
151"M_L_CS_N<6>";
152"M_L_PAR";
153"M_KLM_RST_N";
154"FM_DIMM_EVENT_COD_N";
155"M_L_DQ<3>";
156"M_L_DQ<9>";
157"M_L_DQ<7>";
158"M_L_DQ<5>";
159"M_L_DQ<4>";
160"M_L_DQ<6>";
161"M_L_DQ<8>";
162"M_L_DQ<10>";
163"M_L_DQ<11>";
164"M_L_DQ<12>";
165"M_L_DQ<2>";
166"M_L_DQ<0>";
167"M_L_DQ<1>";
168"FM_ADR_COMPLETE_KLM_N";
169"M_L_ALERT_N";
170"SMB_DDR_KLM_VPP_SDA";
171"SMB_DDR_KLM_VPP_SCL";
172"TP_CH_L_DIMM0_RFU_1";
173"TP_CH_L_DIMM0_RFU_0";
174"TP_CH_L_DIMM0_RFU_2";
175"M_L_VREF";
176"M_L_ACT_N";
%"GND"
"1","(-3525,1525)","2","mstr_symbols","I1";
;
VOLTAGE"0"
CDS_LIB"mstr_symbols"
SIZE"1B"
BOM_COST"MEM"
BODY_TYPE"PLUMBING"
ROOM"DDR4_CH_D"
HDL_POWER"GND";
"A\NAC"13;
%"SCONN288_H44441003"
"2","(1625,3975)","0","mstr_sconn","I100";
;
CDS_SEC"2"
PART_NUMBER"H44441-003"
MATERIAL"SCONN"
LOCATION"J9L2"
BOM_SS"NOPOP"
PACK_TYPE"PIP"
BOM_COST"MEM"
CDS_LIB"mstr_sconn"
SEC_TYPE"PIP"
SEC"2"
CDS_LOCATION"J9L2"
ROOM"DDR4_CH_L";
"DQS0N"
$PN"152"58;
"DQS0P"
$PN"153"60;
"DQS10N"
$PN"19"43;
"DQS10P"
$PN"18"30;
"DQS11N"
$PN"30"29;
"DQS11P"
$PN"29"41;
"DQS12N"
$PN"41"28;
"DQS12P"
$PN"40"27;
"DQS13N"
$PN"100"26;
"DQS13P"
$PN"99"25;
"DQS14N"
$PN"111"24;
"DQS14P"
$PN"110"23;
"DQS15N"
$PN"122"22;
"DQS15P"
$PN"121"53;
"DQS16N"
$PN"133"50;
"DQS16P"
$PN"132"52;
"DQS17N"
$PN"52"49;
"DQS17P"
$PN"51"51;
"DQS1N"
$PN"163"37;
"DQS1P"
$PN"164"36;
"DQS2N"
$PN"174"35;
"DQS2P"
$PN"175"34;
"DQS3N"
$PN"185"33;
"DQS3P"
$PN"186"32;
"DQS4N"
$PN"244"31;
"DQS4P"
$PN"245"59;
"DQS5N"
$PN"255"48;
"DQS5P"
$PN"256"57;
"DQS6N"
$PN"266"47;
"DQS6P"
$PN"267"56;
"DQS7N"
$PN"277"46;
"DQS7P"
$PN"278"55;
"DQS8N"
$PN"196"45;
"DQS8P"
$PN"197"54;
"DQS9N"
$PN"8"44;
"DQS9P"
$PN"7"42;
%"TAP"
"6","(-1625,3775)","0","mstr_standard","I102";
;
CDS_LIB"mstr_standard"
BODY_TYPE"PLUMBING"
HDL_TAP"TRUE";
"B \NAC \NWC"7;
"S \NAC"
BN"1"132;
%"TAP"
"6","(-1625,3825)","0","mstr_standard","I103";
;
CDS_LIB"mstr_standard"
BODY_TYPE"PLUMBING"
HDL_TAP"TRUE";
"B \NAC \NWC"7;
"S \NAC"
BN"2"124;
%"TAP"
"6","(-1625,3875)","0","mstr_standard","I104";
;
CDS_LIB"mstr_standard"
BODY_TYPE"PLUMBING"
HDL_TAP"TRUE";
"B \NAC \NWC"7;
"S \NAC"
BN"3"131;
%"TAP"
"6","(-1625,3975)","0","mstr_standard","I105";
;
CDS_LIB"mstr_standard"
BODY_TYPE"PLUMBING"
HDL_TAP"TRUE";
"B \NAC \NWC"7;
"S \NAC"
BN"5"129;
%"TAP"
"6","(-1625,3925)","0","mstr_standard","I106";
;
CDS_LIB"mstr_standard"
BODY_TYPE"PLUMBING"
HDL_TAP"TRUE";
"B \NAC \NWC"7;
"S \NAC"
BN"4"130;
%"TAP"
"6","(-1625,4025)","0","mstr_standard","I107";
;
CDS_LIB"mstr_standard"
BODY_TYPE"PLUMBING"
HDL_TAP"TRUE";
"B \NAC \NWC"7;
"S \NAC"
BN"6"128;
%"TAP"
"6","(-1625,4125)","0","mstr_standard","I108";
;
CDS_LIB"mstr_standard"
BODY_TYPE"PLUMBING"
HDL_TAP"TRUE";
"B \NAC \NWC"7;
"S \NAC"
BN"8"74;
%"TAP"
"6","(-1625,4075)","0","mstr_standard","I109";
;
CDS_LIB"mstr_standard"
BODY_TYPE"PLUMBING"
HDL_TAP"TRUE";
"B \NAC \NWC"7;
"S \NAC"
BN"7"127;
%"TAP"
"6","(-1625,4175)","0","mstr_standard","I110";
;
CDS_LIB"mstr_standard"
BODY_TYPE"PLUMBING"
HDL_TAP"TRUE";
"B \NAC \NWC"7;
"S \NAC"
BN"9"73;
%"TAP"
"6","(-1625,4225)","0","mstr_standard","I111";
;
CDS_LIB"mstr_standard"
BODY_TYPE"PLUMBING"
HDL_TAP"TRUE";
"B \NAC \NWC"7;
"S \NAC"
BN"10"72;
%"TAP"
"6","(-1625,4275)","0","mstr_standard","I112";
;
CDS_LIB"mstr_standard"
BODY_TYPE"PLUMBING"
HDL_TAP"TRUE";
"B \NAC \NWC"7;
"S \NAC"
BN"11"71;
%"TAP"
"6","(-1625,4375)","0","mstr_standard","I113";
;
CDS_LIB"mstr_standard"
BODY_TYPE"PLUMBING"
HDL_TAP"TRUE";
"B \NAC \NWC"7;
"S \NAC"
BN"13"76;
%"TAP"
"6","(-1625,4325)","0","mstr_standard","I114";
;
CDS_LIB"mstr_standard"
BODY_TYPE"PLUMBING"
HDL_TAP"TRUE";
"B \NAC \NWC"7;
"S \NAC"
BN"12"77;
%"TAP"
"6","(-1625,4425)","0","mstr_standard","I115";
;
CDS_LIB"mstr_standard"
BODY_TYPE"PLUMBING"
HDL_TAP"TRUE";
"B \NAC \NWC"7;
"S \NAC"
BN"14"70;
%"TAP"
"6","(-1625,4475)","0","mstr_standard","I116";
;
CDS_LIB"mstr_standard"
BODY_TYPE"PLUMBING"
HDL_TAP"TRUE";
"B \NAC \NWC"7;
"S \NAC"
BN"15"69;
%"TAP"
"6","(-1625,4525)","0","mstr_standard","I117";
;
CDS_LIB"mstr_standard"
BODY_TYPE"PLUMBING"
HDL_TAP"TRUE";
"B \NAC \NWC"7;
"S \NAC"
BN"16"68;
%"TAP"
"6","(-1625,4575)","0","mstr_standard","I118";
;
CDS_LIB"mstr_standard"
BODY_TYPE"PLUMBING"
HDL_TAP"TRUE";
"B \NAC \NWC"7;
"S \NAC"
BN"17"75;
%"TAP"
"6","(-125,3925)","2","mstr_standard","I119";
;
CDS_LIB"mstr_standard"
BODY_TYPE"PLUMBING"
HDL_TAP"TRUE";
"B \NAC \NWC"1;
"S \NAC"
BN"50"81;
%"SCONN288_H44441003"
"1","(-875,2925)","0","mstr_sconn","I12";
;
CDS_SEC"1"
LOCATION"J9L2"
PART_NUMBER"H44441-003"
MATERIAL"SCONN"
BOM_SS"NOPOP"
PACK_TYPE"PIP"
BOM_COST"MEM"
CDS_LIB"mstr_sconn"
SEC_TYPE"PIP"
SEC"1"
CDS_LOCATION"J9L2"
ROOM"DDR4_CH_L";
"DQ<63>"
$PN"280"67;
"BA<1>"
$PN"224"135;
"CK1N"
$PN"219"120;
"CK0P"
$PN"74"122;
"S3_N_C<1>"
$PN"237"134;
"S2_N_C<0>"
$PN"93"151;
"S1_N"
$PN"89"150;
"DQ<29>"
$PN"181"108;
"DQ<28>"
$PN"36"107;
"C<2>"
$PN"235"136;
"A0"
$PN"79"133;
"A1"
$PN"72"132;
"A12"
$PN"65"77;
"A13"
$PN"232"76;
"A17"
$PN"234"75;
"A3"
$PN"71"131;
"A4"
$PN"214"130;
"A5"
$PN"213"129;
"A6"
$PN"69"128;
"A7"
$PN"211"127;
"A8"
$PN"68"74;
"A9"
$PN"66"73;
"CB<6>"
$PN"54"149;
"CB<5>"
$PN"192"148;
"CB<4>"
$PN"47"147;
"CB<3>"
$PN"201"146;
"CB<2>"
$PN"56"145;
"CB<1>"
$PN"194"144;
"CB<0>"
$PN"49"143;
"CK0N"
$PN"75"119;
"CKE<1>"
$PN"203"142;
"DQ<62>"
$PN"135"38;
"DQ<61>"
$PN"273"39;
"DQ<60>"
$PN"128"66;
"DQ<59>"
$PN"282"65;
"DQ<56>"
$PN"130"64;
"DQ<55>"
$PN"269"63;
"DQ<46>"
$PN"113"87;
"DQ<45>"
$PN"251"86;
"DQ<44>"
$PN"106"85;
"DQ<43>"
$PN"260"98;
"DQ<42>"
$PN"115"97;
"DQ<41>"
$PN"253"96;
"DQ<40>"
$PN"108"95;
"DQ<39>"
$PN"247"94;
"DQ<37>"
$PN"240"93;
"DQ<34>"
$PN"104"92;
"DQ<33>"
$PN"242"91;
"DQ<32>"
$PN"97"106;
"DQ<31>"
$PN"188"105;
"DQ<30>"
$PN"43"104;
"DQ<25>"
$PN"183"103;
"DQ<24>"
$PN"38"102;
"DQ<23>"
$PN"177"101;
"DQ<22>"
$PN"32"118;
"DQ<21>"
$PN"170"117;
"DQ<20>"
$PN"25"116;
"DQ<19>"
$PN"179"115;
"DQ<18>"
$PN"34"114;
"DQ<16>"
$PN"27"113;
"DQ<14>"
$PN"21"112;
"DQ<13>"
$PN"159"111;
"DQ<12>"
$PN"14"164;
"DQ<11>"
$PN"168"163;
"DQ<10>"
$PN"23"162;
"DQ<9>"
$PN"161"156;
"DQ<8>"
$PN"16"161;
"DQ<7>"
$PN"155"157;
"DQ<6>"
$PN"10"160;
"EVENT_N"
$PN"78"154;
"PAR"
$PN"222"152;
"RESET_N"
$PN"58"153;
"RFU<2>"
$PN"144"174;
"SCL"
$PN"141"171;
"SDA"
$PN"285"170;
"VREFCA"
$PN"146"175;
"CK1P"
$PN"218"121;
"BG<0>"
$PN"63"123;
"BG<1>"
$PN"207"126;
"BA<0>"
$PN"81"125;
"SA<0>"
$PN"139"18;
"VDDSPD"
$PN"284"18;
"SA<2>"
$PN"238"13;
"SA<1>"
$PN"140"18;
"DQ<1>"
$PN"150"167;
"DQ<0>"
$PN"5"166;
"ACT_N"
$PN"62"176;
"ALERT_N"
$PN"208"169;
"A2"
$PN"216"124;
"DQ<35>"
$PN"249"90;
"DQ<36>"
$PN"95"89;
"DQ<38>"
$PN"102"88;
"A10"
$PN"225"72;
"A11"
$PN"210"71;
"A14_WE_N"
$PN"228"70;
"A15_CAS_N"
$PN"86"69;
"A16_RAS_N"
$PN"82"68;
"CB<7>"
$PN"199"141;
"ODT<0>"
$PN"87"140;
"ODT<1>"
$PN"91"139;
"CKE<0>"
$PN"60"138;
"S0_N"
$PN"84"137;
"DQ<27>"
$PN"190"100;
"DQ<26>"
$PN"45"99;
"DQ<15>"
$PN"166"110;
"DQ<17>"
$PN"172"109;
"RFU<0>"
$PN"205"173;
"RFU<1>"
$PN"227"172;
"SAVE_N_NC"
$PN"230"168;
"DQ<57>"
$PN"275"62;
"DQ<58>"
$PN"137"61;
"DQ<54>"
$PN"124"40;
"DQ<53>"
$PN"262"84;
"DQ<52>"
$PN"117"83;
"DQ<51>"
$PN"271"82;
"DQ<50>"
$PN"126"81;
"DQ<49>"
$PN"264"80;
"DQ<48>"
$PN"119"79;
"DQ<47>"
$PN"258"78;
"DQ<2>"
$PN"12"165;
"DQ<3>"
$PN"157"155;
"DQ<4>"
$PN"3"159;
"DQ<5>"
$PN"148"158;
%"TAP"
"6","(-125,3975)","2","mstr_standard","I120";
;
CDS_LIB"mstr_standard"
BODY_TYPE"PLUMBING"
HDL_TAP"TRUE";
"B \NAC \NWC"1;
"S \NAC"
BN"51"82;
%"TAP"
"6","(-125,3875)","2","mstr_standard","I121";
;
CDS_LIB"mstr_standard"
BODY_TYPE"PLUMBING"
HDL_TAP"TRUE";
"B \NAC \NWC"1;
"S \NAC"
BN"49"80;
%"TAP"
"6","(-125,3775)","2","mstr_standard","I122";
;
CDS_LIB"mstr_standard"
BODY_TYPE"PLUMBING"
HDL_TAP"TRUE";
"B \NAC \NWC"1;
"S \NAC"
BN"47"78;
%"TAP"
"6","(-125,3825)","2","mstr_standard","I123";
;
CDS_LIB"mstr_standard"
BODY_TYPE"PLUMBING"
HDL_TAP"TRUE";
"B \NAC \NWC"1;
"S \NAC"
BN"48"79;
%"TAP"
"6","(-125,4025)","2","mstr_standard","I124";
;
CDS_LIB"mstr_standard"
BODY_TYPE"PLUMBING"
HDL_TAP"TRUE";
"B \NAC \NWC"1;
"S \NAC"
BN"52"83;
%"TAP"
"6","(-125,4175)","2","mstr_standard","I125";
;
CDS_LIB"mstr_standard"
BODY_TYPE"PLUMBING"
HDL_TAP"TRUE";
"B \NAC \NWC"1;
"S \NAC"
BN"55"63;
%"TAP"
"6","(-125,4225)","2","mstr_standard","I126";
;
CDS_LIB"mstr_standard"
BODY_TYPE"PLUMBING"
HDL_TAP"TRUE";
"B \NAC \NWC"1;
"S \NAC"
BN"56"64;
%"TAP"
"6","(-125,4275)","2","mstr_standard","I127";
;
CDS_LIB"mstr_standard"
BODY_TYPE"PLUMBING"
HDL_TAP"TRUE";
"B \NAC \NWC"1;
"S \NAC"
BN"57"62;
%"TAP"
"6","(-125,4075)","2","mstr_standard","I128";
;
CDS_LIB"mstr_standard"
BODY_TYPE"PLUMBING"
HDL_TAP"TRUE";
"B \NAC \NWC"1;
"S \NAC"
BN"53"84;
%"TAP"
"6","(-125,4125)","2","mstr_standard","I129";
;
CDS_LIB"mstr_standard"
BODY_TYPE"PLUMBING"
HDL_TAP"TRUE";
"B \NAC \NWC"1;
"S \NAC"
BN"54"40;
%"TAP"
"6","(-125,4375)","2","mstr_standard","I130";
;
CDS_LIB"mstr_standard"
BODY_TYPE"PLUMBING"
HDL_TAP"TRUE";
"B \NAC \NWC"1;
"S \NAC"
BN"59"65;
%"TAP"
"6","(-125,4325)","2","mstr_standard","I131";
;
CDS_LIB"mstr_standard"
BODY_TYPE"PLUMBING"
HDL_TAP"TRUE";
"B \NAC \NWC"1;
"S \NAC"
BN"58"61;
%"TAP"
"6","(-125,4525)","2","mstr_standard","I132";
;
CDS_LIB"mstr_standard"
BODY_TYPE"PLUMBING"
HDL_TAP"TRUE";
"B \NAC \NWC"1;
"S \NAC"
BN"62"38;
%"TAP"
"6","(-125,4425)","2","mstr_standard","I133";
;
CDS_LIB"mstr_standard"
BODY_TYPE"PLUMBING"
HDL_TAP"TRUE";
"B \NAC \NWC"1;
"S \NAC"
BN"60"66;
%"TAP"
"6","(-125,4475)","2","mstr_standard","I134";
;
CDS_LIB"mstr_standard"
BODY_TYPE"PLUMBING"
HDL_TAP"TRUE";
"B \NAC \NWC"1;
"S \NAC"
BN"61"39;
%"TAP"
"6","(-125,4575)","2","mstr_standard","I135";
;
CDS_LIB"mstr_standard"
BODY_TYPE"PLUMBING"
HDL_TAP"TRUE";
"B \NAC \NWC"1;
"S \NAC"
BN"63"67;
%"GND"
"1","(2725,775)","2","mstr_symbols","I137";
;
VOLTAGE"0"
SIZE"1B"
CDS_LIB"mstr_symbols"
BOM_COST"MEM"
BODY_TYPE"PLUMBING"
ROOM"DDR4_CH_D"
HDL_POWER"GND";
"A\NAC"14;
%"SCONN288_H44441003"
"3","(3425,2075)","0","mstr_sconn","I138";
;
CDS_SEC"3"
PART_NUMBER"H44441-003"
LOCATION"J9L2"
MATERIAL"SCONN"
BOM_SS"NOPOP"
PACK_TYPE"PIP"
BOM_COST"MEM"
CDS_LIB"mstr_sconn"
SEC_TYPE"PIP"
SEC"3"
CDS_LOCATION"J9L2"
ROOM"DDR4_CH_L";
"VSS<46>"
$PN"147"15;
"VSS<45>"
$PN"149"15;
"VSS<87>"
$PN"15"14;
"VSS<86>"
$PN"17"14;
"VSS<85>"
$PN"20"14;
"VSS<84>"
$PN"22"14;
"VSS<83>"
$PN"24"14;
"VSS<82>"
$PN"26"14;
"VSS<81>"
$PN"28"14;
"VSS<80>"
$PN"31"14;
"VSS<79>"
$PN"33"14;
"VSS<78>"
$PN"35"14;
"VSS<77>"
$PN"37"14;
"VSS<76>"
$PN"39"14;
"VSS<75>"
$PN"42"14;
"VSS<74>"
$PN"44"14;
"VSS<73>"
$PN"46"14;
"VSS<72>"
$PN"48"14;
"VSS<71>"
$PN"50"14;
"VSS<70>"
$PN"53"14;
"VSS<69>"
$PN"55"14;
"VSS<68>"
$PN"57"14;
"VSS<67>"
$PN"94"14;
"VSS<66>"
$PN"96"14;
"VSS<65>"
$PN"98"14;
"VSS<64>"
$PN"101"14;
"VSS<63>"
$PN"103"14;
"VSS<62>"
$PN"105"14;
"VSS<61>"
$PN"107"14;
"VSS<60>"
$PN"109"14;
"VSS<59>"
$PN"112"14;
"VSS<58>"
$PN"114"14;
"VSS<57>"
$PN"116"14;
"VSS<56>"
$PN"118"14;
"VSS<55>"
$PN"120"14;
"VSS<54>"
$PN"123"14;
"VSS<53>"
$PN"125"14;
"VSS<52>"
$PN"127"14;
"VSS<51>"
$PN"129"14;
"VSS<50>"
$PN"131"14;
"VSS<49>"
$PN"134"14;
"VSS<48>"
$PN"136"14;
"VSS<47>"
$PN"138"14;
"VSS<44>"
$PN"151"15;
"VSS<43>"
$PN"154"15;
"VSS<42>"
$PN"156"15;
"VSS<41>"
$PN"158"15;
"VSS<40>"
$PN"160"15;
"VSS<39>"
$PN"162"15;
"VSS<38>"
$PN"165"15;
"VSS<37>"
$PN"167"15;
"VSS<36>"
$PN"169"15;
"VSS<35>"
$PN"171"15;
"VSS<34>"
$PN"173"15;
"VSS<33>"
$PN"176"15;
"VSS<32>"
$PN"178"15;
"VSS<31>"
$PN"180"15;
"VSS<30>"
$PN"182"15;
"VSS<29>"
$PN"184"15;
"VSS<28>"
$PN"187"15;
"VSS<27>"
$PN"189"15;
"VSS<26>"
$PN"191"15;
"VSS<25>"
$PN"193"15;
"VSS<24>"
$PN"195"15;
"VSS<23>"
$PN"198"15;
"VSS<22>"
$PN"200"15;
"VSS<21>"
$PN"202"15;
"VSS<20>"
$PN"239"15;
"VSS<19>"
$PN"241"15;
"VSS<18>"
$PN"243"15;
"VSS<17>"
$PN"246"15;
"VSS<16>"
$PN"248"15;
"VSS<15>"
$PN"250"15;
"VSS<14>"
$PN"252"15;
"VSS<13>"
$PN"254"15;
"VSS<12>"
$PN"257"15;
"VSS<11>"
$PN"259"15;
"VSS<10>"
$PN"261"15;
"VSS<9>"
$PN"263"15;
"VSS<8>"
$PN"265"15;
"VSS<7>"
$PN"268"15;
"VSS<6>"
$PN"270"15;
"VSS<5>"
$PN"272"15;
"VSS<4>"
$PN"274"15;
"VSS<3>"
$PN"276"15;
"VSS<2>"
$PN"279"15;
"VSS<1>"
$PN"281"15;
"VSS<0>"
$PN"283"15;
"VSS<88>"
$PN"13"14;
"VSS<89>"
$PN"11"14;
"VSS<90>"
$PN"9"14;
"VSS<91>"
$PN"6"14;
"VSS<92>"
$PN"4"14;
"VSS<93>"
$PN"2"14;
%"TAP"
"6","(2325,3125)","2","mstr_standard","I142";
;
CDS_LIB"mstr_standard"
BODY_TYPE"PLUMBING"
HDL_TAP"TRUE";
"B \NAC \NWC"11;
"S \NAC"
BN"0"60;
%"TAP"
"6","(2325,3225)","2","mstr_standard","I143";
;
CDS_LIB"mstr_standard"
BODY_TYPE"PLUMBING"
HDL_TAP"TRUE";
"B \NAC \NWC"11;
"S \NAC"
BN"1"36;
%"TAP"
"6","(2525,3075)","2","mstr_standard","I144";
;
CDS_LIB"mstr_standard"
BODY_TYPE"PLUMBING"
HDL_TAP"TRUE";
"B \NAC \NWC"12;
"S \NAC"
BN"0"58;
%"TAP"
"6","(2525,3175)","2","mstr_standard","I145";
;
CDS_LIB"mstr_standard"
BODY_TYPE"PLUMBING"
HDL_TAP"TRUE";
"B \NAC \NWC"12;
"S \NAC"
BN"1"37;
%"TAP"
"6","(2325,3325)","2","mstr_standard","I146";
;
CDS_LIB"mstr_standard"
BODY_TYPE"PLUMBING"
HDL_TAP"TRUE";
"B \NAC \NWC"11;
"S \NAC"
BN"2"34;
%"TAP"
"6","(2325,3425)","2","mstr_standard","I147";
;
CDS_LIB"mstr_standard"
BODY_TYPE"PLUMBING"
HDL_TAP"TRUE";
"B \NAC \NWC"11;
"S \NAC"
BN"3"32;
%"TAP"
"6","(2325,3625)","2","mstr_standard","I148";
;
CDS_LIB"mstr_standard"
BODY_TYPE"PLUMBING"
HDL_TAP"TRUE";
"B \NAC \NWC"11;
"S \NAC"
BN"5"57;
%"TAP"
"6","(2325,3525)","2","mstr_standard","I149";
;
CDS_LIB"mstr_standard"
BODY_TYPE"PLUMBING"
HDL_TAP"TRUE";
"B \NAC \NWC"11;
"S \NAC"
BN"4"59;
%"TAP"
"6","(2325,3725)","2","mstr_standard","I150";
;
CDS_LIB"mstr_standard"
BODY_TYPE"PLUMBING"
HDL_TAP"TRUE";
"B \NAC \NWC"11;
"S \NAC"
BN"6"56;
%"TAP"
"6","(2525,3475)","2","mstr_standard","I151";
;
CDS_LIB"mstr_standard"
BODY_TYPE"PLUMBING"
HDL_TAP"TRUE";
"B \NAC \NWC"12;
"S \NAC"
BN"4"31;
%"TAP"
"6","(2525,3275)","2","mstr_standard","I152";
;
CDS_LIB"mstr_standard"
BODY_TYPE"PLUMBING"
HDL_TAP"TRUE";
"B \NAC \NWC"12;
"S \NAC"
BN"2"35;
%"TAP"
"6","(2525,3375)","2","mstr_standard","I153";
;
CDS_LIB"mstr_standard"
BODY_TYPE"PLUMBING"
HDL_TAP"TRUE";
"B \NAC \NWC"12;
"S \NAC"
BN"3"33;
%"TAP"
"6","(2525,3675)","2","mstr_standard","I154";
;
CDS_LIB"mstr_standard"
BODY_TYPE"PLUMBING"
HDL_TAP"TRUE";
"B \NAC \NWC"12;
"S \NAC"
BN"6"47;
%"TAP"
"6","(2525,3575)","2","mstr_standard","I155";
;
CDS_LIB"mstr_standard"
BODY_TYPE"PLUMBING"
HDL_TAP"TRUE";
"B \NAC \NWC"12;
"S \NAC"
BN"5"48;
%"GND"
"1","(4125,775)","2","mstr_symbols","I156";
;
VOLTAGE"0"
SIZE"1B"
CDS_LIB"mstr_symbols"
BOM_COST"MEM"
BODY_TYPE"PLUMBING"
ROOM"DDR4_CH_D"
HDL_POWER"GND";
"A\NAC"15;
%"TAP"
"6","(2325,3825)","2","mstr_standard","I157";
;
CDS_LIB"mstr_standard"
BODY_TYPE"PLUMBING"
HDL_TAP"TRUE";
"B \NAC \NWC"11;
"S \NAC"
BN"7"55;
%"TAP"
"6","(2325,4025)","2","mstr_standard","I158";
;
CDS_LIB"mstr_standard"
BODY_TYPE"PLUMBING"
HDL_TAP"TRUE";
"B \NAC \NWC"11;
"S \NAC"
BN"9"42;
%"TAP"
"6","(2325,3925)","2","mstr_standard","I159";
;
CDS_LIB"mstr_standard"
BODY_TYPE"PLUMBING"
HDL_TAP"TRUE";
"B \NAC \NWC"11;
"S \NAC"
BN"8"54;
%"TAP"
"6","(2325,4125)","2","mstr_standard","I160";
;
CDS_LIB"mstr_standard"
BODY_TYPE"PLUMBING"
HDL_TAP"TRUE";
"B \NAC \NWC"11;
"S \NAC"
BN"10"30;
%"TAP"
"6","(2325,4225)","2","mstr_standard","I161";
;
CDS_LIB"mstr_standard"
BODY_TYPE"PLUMBING"
HDL_TAP"TRUE";
"B \NAC \NWC"11;
"S \NAC"
BN"11"41;
%"TAP"
"6","(2525,3975)","2","mstr_standard","I162";
;
CDS_LIB"mstr_standard"
BODY_TYPE"PLUMBING"
HDL_TAP"TRUE";
"B \NAC \NWC"12;
"S \NAC"
BN"9"44;
%"TAP"
"6","(2525,3775)","2","mstr_standard","I163";
;
CDS_LIB"mstr_standard"
BODY_TYPE"PLUMBING"
HDL_TAP"TRUE";
"B \NAC \NWC"12;
"S \NAC"
BN"7"46;
%"TAP"
"6","(2525,3875)","2","mstr_standard","I164";
;
CDS_LIB"mstr_standard"
BODY_TYPE"PLUMBING"
HDL_TAP"TRUE";
"B \NAC \NWC"12;
"S \NAC"
BN"8"45;
%"TAP"
"6","(2525,4175)","2","mstr_standard","I165";
;
CDS_LIB"mstr_standard"
BODY_TYPE"PLUMBING"
HDL_TAP"TRUE";
"B \NAC \NWC"12;
"S \NAC"
BN"11"29;
%"TAP"
"6","(2525,4075)","2","mstr_standard","I166";
;
CDS_LIB"mstr_standard"
BODY_TYPE"PLUMBING"
HDL_TAP"TRUE";
"B \NAC \NWC"12;
"S \NAC"
BN"10"43;
%"TAP"
"6","(2525,4275)","2","mstr_standard","I167";
;
CDS_LIB"mstr_standard"
BODY_TYPE"PLUMBING"
HDL_TAP"TRUE";
"B \NAC \NWC"12;
"S \NAC"
BN"12"28;
%"TAP"
"6","(2325,4325)","2","mstr_standard","I168";
;
CDS_LIB"mstr_standard"
BODY_TYPE"PLUMBING"
HDL_TAP"TRUE";
"B \NAC \NWC"11;
"S \NAC"
BN"12"27;
%"TAP"
"6","(2325,4525)","2","mstr_standard","I169";
;
CDS_LIB"mstr_standard"
BODY_TYPE"PLUMBING"
HDL_TAP"TRUE";
"B \NAC \NWC"11;
"S \NAC"
BN"14"23;
%"TAP"
"6","(-1625,2225)","0","mstr_standard","I17";
;
CDS_LIB"mstr_standard"
BODY_TYPE"PLUMBING"
HDL_TAP"TRUE";
"B \NAC \NWC"3;
"S \NAC"
BN"1"144;
%"TAP"
"6","(2325,4425)","2","mstr_standard","I170";
;
CDS_LIB"mstr_standard"
BODY_TYPE"PLUMBING"
HDL_TAP"TRUE";
"B \NAC \NWC"11;
"S \NAC"
BN"13"25;
%"TAP"
"6","(2325,4625)","2","mstr_standard","I171";
;
CDS_LIB"mstr_standard"
BODY_TYPE"PLUMBING"
HDL_TAP"TRUE";
"B \NAC \NWC"11;
"S \NAC"
BN"15"53;
%"TAP"
"6","(2325,4725)","2","mstr_standard","I172";
;
CDS_LIB"mstr_standard"
BODY_TYPE"PLUMBING"
HDL_TAP"TRUE";
"B \NAC \NWC"11;
"S \NAC"
BN"16"52;
%"TAP"
"6","(2525,4375)","2","mstr_standard","I173";
;
CDS_LIB"mstr_standard"
BODY_TYPE"PLUMBING"
HDL_TAP"TRUE";
"B \NAC \NWC"12;
"S \NAC"
BN"13"26;
%"TAP"
"6","(2525,4475)","2","mstr_standard","I174";
;
CDS_LIB"mstr_standard"
BODY_TYPE"PLUMBING"
HDL_TAP"TRUE";
"B \NAC \NWC"12;
"S \NAC"
BN"14"24;
%"TAP"
"6","(2525,4775)","2","mstr_standard","I175";
;
CDS_LIB"mstr_standard"
BODY_TYPE"PLUMBING"
HDL_TAP"TRUE";
"B \NAC \NWC"12;
"S \NAC"
BN"17"49;
%"TAP"
"6","(2525,4675)","2","mstr_standard","I176";
;
CDS_LIB"mstr_standard"
BODY_TYPE"PLUMBING"
HDL_TAP"TRUE";
"B \NAC \NWC"12;
"S \NAC"
BN"16"50;
%"TAP"
"6","(2525,4575)","2","mstr_standard","I177";
;
CDS_LIB"mstr_standard"
BODY_TYPE"PLUMBING"
HDL_TAP"TRUE";
"B \NAC \NWC"12;
"S \NAC"
BN"15"22;
%"TAP"
"6","(2325,4825)","2","mstr_standard","I178";
;
CDS_LIB"mstr_standard"
BODY_TYPE"PLUMBING"
HDL_TAP"TRUE";
"B \NAC \NWC"11;
"S \NAC"
BN"17"51;
%"TAP"
"6","(-1625,2175)","0","mstr_standard","I18";
;
CDS_LIB"mstr_standard"
BODY_TYPE"PLUMBING"
HDL_TAP"TRUE";
"B \NAC \NWC"3;
"S \NAC"
BN"0"143;
%"P12V_NVDIMM_KLM"
"1","(2000,2700)","0","mstr_symbols","I181";
;
VOLTAGE"12.0"
CDS_LIB"mstr_symbols"
BODY_TYPE"PLUMBING"
HDL_POWER"P12V_NVDIMM_KLM";
"G\NAC"16;
%"CAP_A"
"1","(-3025,1225)","2","dev_discrete","I182";
;
LOCATION"C1A17"
PART_NUMBER"A36096-045"
VALUE"0.01UF"
TOLERANCE"10%"
PACK_TYPE"0402V"
VOLTAGE"25V"
MATERIAL"X7R"
CDS_LOCATION"C1A17"
BOM_COST"MEM"
CDS_LIB"dev_discrete"
CDS_SEC"1"
$SEC"1"
ROOM"DDR4_CH_D";
"B"
$PN"2"17;
"A"
$PN"1"175;
%"TAP"
"6","(-1625,2325)","0","mstr_standard","I19";
;
CDS_LIB"mstr_standard"
BODY_TYPE"PLUMBING"
HDL_TAP"TRUE";
"B \NAC \NWC"3;
"S \NAC"
BN"3"146;
%"GND"
"1","(-3025,975)","0","mstr_symbols","I2";
;
VOLTAGE"0"
SIZE"1B"
CDS_LIB"mstr_symbols"
BOM_COST"MEM"
BODY_TYPE"PLUMBING"
ROOM"DDR4_CH_D"
HDL_POWER"GND";
"A\NAC"17;
%"TAP"
"6","(-1625,2275)","0","mstr_standard","I20";
;
CDS_LIB"mstr_standard"
BODY_TYPE"PLUMBING"
HDL_TAP"TRUE";
"B \NAC \NWC"3;
"S \NAC"
BN"2"145;
%"TAP"
"6","(-1625,2375)","0","mstr_standard","I21";
;
CDS_LIB"mstr_standard"
BODY_TYPE"PLUMBING"
HDL_TAP"TRUE";
"B \NAC \NWC"3;
"S \NAC"
BN"4"147;
%"TAP"
"6","(-1625,2425)","0","mstr_standard","I22";
;
CDS_LIB"mstr_standard"
BODY_TYPE"PLUMBING"
HDL_TAP"TRUE";
"B \NAC \NWC"3;
"S \NAC"
BN"5"148;
%"TAP"
"6","(-1625,2475)","0","mstr_standard","I23";
;
CDS_LIB"mstr_standard"
BODY_TYPE"PLUMBING"
HDL_TAP"TRUE";
"B \NAC \NWC"3;
"S \NAC"
BN"6"149;
%"TAP"
"6","(-1625,2525)","0","mstr_standard","I24";
;
CDS_LIB"mstr_standard"
BODY_TYPE"PLUMBING"
HDL_TAP"TRUE";
"B \NAC \NWC"3;
"S \NAC"
BN"7"141;
%"TAP"
"6","(-1625,2675)","0","mstr_standard","I25";
;
CDS_LIB"mstr_standard"
BODY_TYPE"PLUMBING"
HDL_TAP"TRUE";
"B \NAC \NWC"5;
"S \NAC"
BN"3"139;
%"TAP"
"6","(-1625,2625)","0","mstr_standard","I26";
;
CDS_LIB"mstr_standard"
BODY_TYPE"PLUMBING"
HDL_TAP"TRUE";
"B \NAC \NWC"5;
"S \NAC"
BN"2"140;
%"TAP"
"6","(-1825,3225)","0","mstr_standard","I34";
;
CDS_LIB"mstr_standard"
BODY_TYPE"PLUMBING"
HDL_TAP"TRUE";
"B \NAC \NWC"10;
"S \NAC"
BN"2"119;
%"TAP"
"6","(-1625,2825)","0","mstr_standard","I35";
;
CDS_LIB"mstr_standard"
BODY_TYPE"PLUMBING"
HDL_TAP"TRUE";
"B \NAC \NWC"4;
"S \NAC"
BN"3"142;
%"TAP"
"6","(-1625,2775)","0","mstr_standard","I36";
;
CDS_LIB"mstr_standard"
BODY_TYPE"PLUMBING"
HDL_TAP"TRUE";
"B \NAC \NWC"4;
"S \NAC"
BN"2"138;
%"TAP"
"6","(-1625,2975)","0","mstr_standard","I37";
;
CDS_LIB"mstr_standard"
BODY_TYPE"PLUMBING"
HDL_TAP"TRUE";
"B \NAC \NWC"2;
"S \NAC"
BN"5"150;
%"TAP"
"6","(-1625,2925)","0","mstr_standard","I38";
;
CDS_LIB"mstr_standard"
BODY_TYPE"PLUMBING"
HDL_TAP"TRUE";
"B \NAC \NWC"2;
"S \NAC"
BN"4"137;
%"TAP"
"6","(-1625,3075)","0","mstr_standard","I39";
;
CDS_LIB"mstr_standard"
BODY_TYPE"PLUMBING"
HDL_TAP"TRUE";
"B \NAC \NWC"2;
"S \NAC"
BN"7"134;
%"TAP"
"6","(-1625,3025)","0","mstr_standard","I40";
;
CDS_LIB"mstr_standard"
BODY_TYPE"PLUMBING"
HDL_TAP"TRUE";
"B \NAC \NWC"2;
"S \NAC"
BN"6"151;
%"TAP"
"6","(-1825,3325)","0","mstr_standard","I41";
;
CDS_LIB"mstr_standard"
BODY_TYPE"PLUMBING"
HDL_TAP"TRUE";
"B \NAC \NWC"10;
"S \NAC"
BN"3"120;
%"TAP"
"6","(-1625,3275)","0","mstr_standard","I42";
;
CDS_LIB"mstr_standard"
BODY_TYPE"PLUMBING"
HDL_TAP"TRUE";
"B \NAC \NWC"9;
"S \NAC"
BN"2"122;
%"TAP"
"6","(-1625,3375)","0","mstr_standard","I43";
;
CDS_LIB"mstr_standard"
BODY_TYPE"PLUMBING"
HDL_TAP"TRUE";
"B \NAC \NWC"9;
"S \NAC"
BN"3"121;
%"TAP"
"6","(-1625,3475)","0","mstr_standard","I44";
;
CDS_LIB"mstr_standard"
BODY_TYPE"PLUMBING"
HDL_TAP"TRUE";
"B \NAC \NWC"8;
"S \NAC"
BN"0"123;
%"TAP"
"6","(-1625,3575)","0","mstr_standard","I45";
;
CDS_LIB"mstr_standard"
BODY_TYPE"PLUMBING"
HDL_TAP"TRUE";
"B \NAC \NWC"6;
"S \NAC"
BN"0"125;
%"TAP"
"6","(-1625,3525)","0","mstr_standard","I46";
;
CDS_LIB"mstr_standard"
BODY_TYPE"PLUMBING"
HDL_TAP"TRUE";
"B \NAC \NWC"8;
"S \NAC"
BN"1"126;
%"TAP"
"6","(-1625,3625)","0","mstr_standard","I47";
;
CDS_LIB"mstr_standard"
BODY_TYPE"PLUMBING"
HDL_TAP"TRUE";
"B \NAC \NWC"6;
"S \NAC"
BN"1"135;
%"TAP"
"6","(-1625,3725)","0","mstr_standard","I48";
;
CDS_LIB"mstr_standard"
BODY_TYPE"PLUMBING"
HDL_TAP"TRUE";
"B \NAC \NWC"7;
"S \NAC"
BN"0"133;
%"TAP"
"6","(-125,1425)","2","mstr_standard","I49";
;
CDS_LIB"mstr_standard"
BODY_TYPE"PLUMBING"
HDL_TAP"TRUE";
"B \NAC \NWC"1;
"S \NAC"
BN"0"166;
%"PVPP_KLM"
"1","(-3525,1925)","0","mstr_symbols","I5";
;
VOLTAGE"2.5V"
BOM_COST"MEM"
CDS_LIB"mstr_symbols"
BODY_TYPE"PLUMBING"
ROOM"DDR4_CH_D"
HDL_POWER"PVPP_KLM";
"G\NAC"18;
%"TAP"
"6","(-125,1625)","2","mstr_standard","I50";
;
CDS_LIB"mstr_standard"
BODY_TYPE"PLUMBING"
HDL_TAP"TRUE";
"B \NAC \NWC"1;
"S \NAC"
BN"4"159;
%"TAP"
"6","(-125,1475)","2","mstr_standard","I51";
;
CDS_LIB"mstr_standard"
BODY_TYPE"PLUMBING"
HDL_TAP"TRUE";
"B \NAC \NWC"1;
"S \NAC"
BN"1"167;
%"TAP"
"6","(-125,1525)","2","mstr_standard","I52";
;
CDS_LIB"mstr_standard"
BODY_TYPE"PLUMBING"
HDL_TAP"TRUE";
"B \NAC \NWC"1;
"S \NAC"
BN"2"165;
%"TAP"
"6","(-125,1675)","2","mstr_standard","I53";
;
CDS_LIB"mstr_standard"
BODY_TYPE"PLUMBING"
HDL_TAP"TRUE";
"B \NAC \NWC"1;
"S \NAC"
BN"5"158;
%"TAP"
"6","(-125,1575)","2","mstr_standard","I54";
;
CDS_LIB"mstr_standard"
BODY_TYPE"PLUMBING"
HDL_TAP"TRUE";
"B \NAC \NWC"1;
"S \NAC"
BN"3"155;
%"SCONN288_H44441003"
"4","(1375,1725)","0","mstr_sconn","I55";
;
CDS_SEC"4"
PART_NUMBER"H44441-003"
MATERIAL"SCONN"
LOCATION"J9L2"
BOM_SS"NOPOP"
PACK_TYPE"PIP"
BOM_COST"MEM"
CDS_LIB"mstr_sconn"
SEC_TYPE"PIP"
SEC"4"
CDS_LOCATION"J9L2"
ROOM"DDR4_CH_L";
"VDD<0>"
$PN"236"19;
"VDD<6>"
$PN"220"19;
"VDD<10>"
$PN"209"19;
"VDD<13>"
$PN"92"19;
"VDD<16>"
$PN"85"19;
"VDD<19>"
$PN"76"19;
"VDD<23>"
$PN"64"19;
"VDD<25>"
$PN"59"19;
"VTT<0>"
$PN"221"20;
"12V<1>"
$PN"1"16;
"12V<0>"
$PN"145"16;
"VDD<24>"
$PN"61"19;
"VDD<22>"
$PN"67"19;
"VDD<21>"
$PN"70"19;
"VDD<20>"
$PN"73"19;
"VDD<18>"
$PN"80"19;
"VDD<17>"
$PN"83"19;
"VDD<15>"
$PN"88"19;
"VDD<14>"
$PN"90"19;
"VDD<12>"
$PN"204"19;
"VDD<11>"
$PN"206"19;
"VDD<9>"
$PN"212"19;
"VDD<8>"
$PN"215"19;
"VDD<7>"
$PN"217"19;
"VDD<5>"
$PN"223"19;
"VDD<4>"
$PN"226"19;
"VDD<3>"
$PN"229"19;
"VDD<2>"
$PN"231"19;
"VDD<1>"
$PN"233"19;
"VPP<4>"
$PN"142"21;
"VPP<3>"
$PN"143"21;
"VPP<2>"
$PN"288"21;
"VPP<1>"
$PN"286"21;
"VPP<0>"
$PN"287"21;
"VTT<1>"
$PN"77"20;
%"TAP"
"6","(-125,1925)","2","mstr_standard","I56";
;
CDS_LIB"mstr_standard"
BODY_TYPE"PLUMBING"
HDL_TAP"TRUE";
"B \NAC \NWC"1;
"S \NAC"
BN"10"162;
%"TAP"
"6","(-125,1725)","2","mstr_standard","I57";
;
CDS_LIB"mstr_standard"
BODY_TYPE"PLUMBING"
HDL_TAP"TRUE";
"B \NAC \NWC"1;
"S \NAC"
BN"6"160;
%"TAP"
"6","(-125,1825)","2","mstr_standard","I58";
;
CDS_LIB"mstr_standard"
BODY_TYPE"PLUMBING"
HDL_TAP"TRUE";
"B \NAC \NWC"1;
"S \NAC"
BN"8"161;
%"TAP"
"6","(-125,1775)","2","mstr_standard","I59";
;
CDS_LIB"mstr_standard"
BODY_TYPE"PLUMBING"
HDL_TAP"TRUE";
"B \NAC \NWC"1;
"S \NAC"
BN"7"157;
%"TAP"
"6","(-125,1975)","2","mstr_standard","I60";
;
CDS_LIB"mstr_standard"
BODY_TYPE"PLUMBING"
HDL_TAP"TRUE";
"B \NAC \NWC"1;
"S \NAC"
BN"11"163;
%"TAP"
"6","(-125,1875)","2","mstr_standard","I61";
;
CDS_LIB"mstr_standard"
BODY_TYPE"PLUMBING"
HDL_TAP"TRUE";
"B \NAC \NWC"1;
"S \NAC"
BN"9"156;
%"TAP"
"6","(-125,2025)","2","mstr_standard","I62";
;
CDS_LIB"mstr_standard"
BODY_TYPE"PLUMBING"
HDL_TAP"TRUE";
"B \NAC \NWC"1;
"S \NAC"
BN"12"164;
%"TAP"
"6","(-125,2075)","2","mstr_standard","I63";
;
CDS_LIB"mstr_standard"
BODY_TYPE"PLUMBING"
HDL_TAP"TRUE";
"B \NAC \NWC"1;
"S \NAC"
BN"13"111;
%"TAP"
"6","(-125,2225)","2","mstr_standard","I64";
;
CDS_LIB"mstr_standard"
BODY_TYPE"PLUMBING"
HDL_TAP"TRUE";
"B \NAC \NWC"1;
"S \NAC"
BN"16"113;
%"TAP"
"6","(-125,2175)","2","mstr_standard","I65";
;
CDS_LIB"mstr_standard"
BODY_TYPE"PLUMBING"
HDL_TAP"TRUE";
"B \NAC \NWC"1;
"S \NAC"
BN"15"110;
%"TAP"
"6","(-125,2125)","2","mstr_standard","I66";
;
CDS_LIB"mstr_standard"
BODY_TYPE"PLUMBING"
HDL_TAP"TRUE";
"B \NAC \NWC"1;
"S \NAC"
BN"14"112;
%"TAP"
"6","(-125,2325)","2","mstr_standard","I67";
;
CDS_LIB"mstr_standard"
BODY_TYPE"PLUMBING"
HDL_TAP"TRUE";
"B \NAC \NWC"1;
"S \NAC"
BN"18"114;
%"TAP"
"6","(-125,2275)","2","mstr_standard","I68";
;
CDS_LIB"mstr_standard"
BODY_TYPE"PLUMBING"
HDL_TAP"TRUE";
"B \NAC \NWC"1;
"S \NAC"
BN"17"109;
%"TAP"
"6","(-125,2475)","2","mstr_standard","I69";
;
CDS_LIB"mstr_standard"
BODY_TYPE"PLUMBING"
HDL_TAP"TRUE";
"B \NAC \NWC"1;
"S \NAC"
BN"21"117;
%"TAP"
"6","(-125,2425)","2","mstr_standard","I70";
;
CDS_LIB"mstr_standard"
BODY_TYPE"PLUMBING"
HDL_TAP"TRUE";
"B \NAC \NWC"1;
"S \NAC"
BN"20"116;
%"TAP"
"6","(-125,2375)","2","mstr_standard","I71";
;
CDS_LIB"mstr_standard"
BODY_TYPE"PLUMBING"
HDL_TAP"TRUE";
"B \NAC \NWC"1;
"S \NAC"
BN"19"115;
%"TAP"
"6","(-125,2675)","2","mstr_standard","I72";
;
CDS_LIB"mstr_standard"
BODY_TYPE"PLUMBING"
HDL_TAP"TRUE";
"B \NAC \NWC"1;
"S \NAC"
BN"25"103;
%"TAP"
"6","(-125,2625)","2","mstr_standard","I73";
;
CDS_LIB"mstr_standard"
BODY_TYPE"PLUMBING"
HDL_TAP"TRUE";
"B \NAC \NWC"1;
"S \NAC"
BN"24"102;
%"TAP"
"6","(-125,2725)","2","mstr_standard","I74";
;
CDS_LIB"mstr_standard"
BODY_TYPE"PLUMBING"
HDL_TAP"TRUE";
"B \NAC \NWC"1;
"S \NAC"
BN"26"99;
%"TAP"
"6","(-125,2525)","2","mstr_standard","I75";
;
CDS_LIB"mstr_standard"
BODY_TYPE"PLUMBING"
HDL_TAP"TRUE";
"B \NAC \NWC"1;
"S \NAC"
BN"22"118;
%"TAP"
"6","(-125,2575)","2","mstr_standard","I76";
;
CDS_LIB"mstr_standard"
BODY_TYPE"PLUMBING"
HDL_TAP"TRUE";
"B \NAC \NWC"1;
"S \NAC"
BN"23"101;
%"PVDDQ_KLM"
"1","(275,2275)","0","mstr_symbols","I77";
;
VOLTAGE"1.2V"
BOM_COST"MEM"
CDS_LIB"mstr_symbols"
BODY_TYPE"PLUMBING"
ROOM"DDR4_CH_D"
HDL_POWER"PVDDQ_KLM";
"G\NAC"19;
%"PVTT_KLM"
"1","(525,2425)","0","mstr_symbols","I78";
;
VOLTAGE"0.6V"
BOM_COST"MEM"
CDS_LIB"mstr_symbols"
BODY_TYPE"PLUMBING"
ROOM"DDR4_CH_D"
HDL_POWER"PVTT_KLM";
"G\NAC"20;
%"TAP"
"6","(-125,2775)","2","mstr_standard","I79";
;
CDS_LIB"mstr_standard"
BODY_TYPE"PLUMBING"
HDL_TAP"TRUE";
"B \NAC \NWC"1;
"S \NAC"
BN"27"100;
%"TAP"
"6","(-125,2825)","2","mstr_standard","I80";
;
CDS_LIB"mstr_standard"
BODY_TYPE"PLUMBING"
HDL_TAP"TRUE";
"B \NAC \NWC"1;
"S \NAC"
BN"28"107;
%"TAP"
"6","(-125,2875)","2","mstr_standard","I81";
;
CDS_LIB"mstr_standard"
BODY_TYPE"PLUMBING"
HDL_TAP"TRUE";
"B \NAC \NWC"1;
"S \NAC"
BN"29"108;
%"TAP"
"6","(-125,2975)","2","mstr_standard","I82";
;
CDS_LIB"mstr_standard"
BODY_TYPE"PLUMBING"
HDL_TAP"TRUE";
"B \NAC \NWC"1;
"S \NAC"
BN"31"105;
%"TAP"
"6","(-125,2925)","2","mstr_standard","I83";
;
CDS_LIB"mstr_standard"
BODY_TYPE"PLUMBING"
HDL_TAP"TRUE";
"B \NAC \NWC"1;
"S \NAC"
BN"30"104;
%"TAP"
"6","(-125,3175)","2","mstr_standard","I84";
;
CDS_LIB"mstr_standard"
BODY_TYPE"PLUMBING"
HDL_TAP"TRUE";
"B \NAC \NWC"1;
"S \NAC"
BN"35"90;
%"TAP"
"6","(-125,3125)","2","mstr_standard","I85";
;
CDS_LIB"mstr_standard"
BODY_TYPE"PLUMBING"
HDL_TAP"TRUE";
"B \NAC \NWC"1;
"S \NAC"
BN"34"92;
%"TAP"
"6","(-125,3225)","2","mstr_standard","I86";
;
CDS_LIB"mstr_standard"
BODY_TYPE"PLUMBING"
HDL_TAP"TRUE";
"B \NAC \NWC"1;
"S \NAC"
BN"36"89;
%"TAP"
"6","(-125,3075)","2","mstr_standard","I87";
;
CDS_LIB"mstr_standard"
BODY_TYPE"PLUMBING"
HDL_TAP"TRUE";
"B \NAC \NWC"1;
"S \NAC"
BN"33"91;
%"TAP"
"6","(-125,3025)","2","mstr_standard","I88";
;
CDS_LIB"mstr_standard"
BODY_TYPE"PLUMBING"
HDL_TAP"TRUE";
"B \NAC \NWC"1;
"S \NAC"
BN"32"106;
%"TAP"
"6","(-125,3325)","2","mstr_standard","I89";
;
CDS_LIB"mstr_standard"
BODY_TYPE"PLUMBING"
HDL_TAP"TRUE";
"B \NAC \NWC"1;
"S \NAC"
BN"38"88;
%"TAP"
"6","(-125,3275)","2","mstr_standard","I90";
;
CDS_LIB"mstr_standard"
BODY_TYPE"PLUMBING"
HDL_TAP"TRUE";
"B \NAC \NWC"1;
"S \NAC"
BN"37"93;
%"TAP"
"6","(-125,3425)","2","mstr_standard","I91";
;
CDS_LIB"mstr_standard"
BODY_TYPE"PLUMBING"
HDL_TAP"TRUE";
"B \NAC \NWC"1;
"S \NAC"
BN"40"95;
%"TAP"
"6","(-125,3375)","2","mstr_standard","I92";
;
CDS_LIB"mstr_standard"
BODY_TYPE"PLUMBING"
HDL_TAP"TRUE";
"B \NAC \NWC"1;
"S \NAC"
BN"39"94;
%"TAP"
"6","(-125,3475)","2","mstr_standard","I93";
;
CDS_LIB"mstr_standard"
BODY_TYPE"PLUMBING"
HDL_TAP"TRUE";
"B \NAC \NWC"1;
"S \NAC"
BN"41"96;
%"TAP"
"6","(-125,3625)","2","mstr_standard","I94";
;
CDS_LIB"mstr_standard"
BODY_TYPE"PLUMBING"
HDL_TAP"TRUE";
"B \NAC \NWC"1;
"S \NAC"
BN"44"85;
%"TAP"
"6","(-125,3675)","2","mstr_standard","I95";
;
CDS_LIB"mstr_standard"
BODY_TYPE"PLUMBING"
HDL_TAP"TRUE";
"B \NAC \NWC"1;
"S \NAC"
BN"45"86;
%"TAP"
"6","(-125,3725)","2","mstr_standard","I96";
;
CDS_LIB"mstr_standard"
BODY_TYPE"PLUMBING"
HDL_TAP"TRUE";
"B \NAC \NWC"1;
"S \NAC"
BN"46"87;
%"TAP"
"6","(-125,3575)","2","mstr_standard","I97";
;
CDS_LIB"mstr_standard"
BODY_TYPE"PLUMBING"
HDL_TAP"TRUE";
"B \NAC \NWC"1;
"S \NAC"
BN"43"98;
%"TAP"
"6","(-125,3525)","2","mstr_standard","I98";
;
CDS_LIB"mstr_standard"
BODY_TYPE"PLUMBING"
HDL_TAP"TRUE";
"B \NAC \NWC"1;
"S \NAC"
BN"42"97;
%"PVPP_KLM"
"1","(675,2750)","0","mstr_symbols","I99";
;
VOLTAGE"2.5V"
BOM_COST"MEM"
CDS_LIB"mstr_symbols"
BODY_TYPE"PLUMBING"
ROOM"DDR4_CH_D"
HDL_POWER"PVPP_KLM";
"G\NAC"21;
END.
